# BASEBOARD_FAB2 (Tioga Pass) — schematic netlist excerpt (pin names and nets, part order shuffled) for the footprints in the layout excerpt that follows; sources: Cadence DE-HDL packaged netlist, KiCad conversion of Wiwynn_Tioga_Pass_MB.brd

C2D24  CAP_A  22.0UF 4V 20% X6S  pkg 0603V  page 76 : A = PVCCIN_CPU1 ; B = GND
C2D20  CAP_A  22.0UF 4V 20% X6S  pkg 0603V  page 76 : A = PVCCIN_CPU1 ; B = GND
C7E13  SC22U16V5MX-4-GP  20%  pkg SMD-BCG5  page 241 : \1\ = VR_FET_SW_P5V_STBY_PVIN ; \2\ = GND
C4D31  CAP_A  1.0UF 6.3V 10% X6S  pkg 0402V  page 213 : A = VR_PVCCIO_CPU1_VD12 ; B = GND

(kicad_pcb
	(version 20260206)
	(generator "pcbnew")
	(generator_version "10.0")
	(general
		(thickness 1.6)
		(legacy_teardrops no)
	)
	(paper "A4")
	(title_block
		(title "Wiwynn_Tioga_Pass_MB.brd")
		(comment 1 "Tioga Pass / footprints 68-71 of 4770")
	)
	(layers
		(0 "F.Cu" signal "TOP")
		(4 "In1.Cu" signal "L2GND")
		(6 "In2.Cu" signal "L3")
		(8 "In3.Cu" signal "L4GND")
		(10 "In4.Cu" signal "L5")
		(12 "In5.Cu" signal "L6GND")
		(14 "In6.Cu" signal "L7VCC")
		(16 "In7.Cu" signal "L8VCC")
		(18 "In8.Cu" signal "L9GND")
		(20 "In9.Cu" signal "L10")
		(22 "In10.Cu" signal "L11GND")
		(24 "In11.Cu" signal "L12")
		(26 "In12.Cu" signal "L13GND")
		(2 "B.Cu" signal "BOTTOM")
		(9 "F.Adhes" user "F.Adhesive")
		(11 "B.Adhes" user "B.Adhesive")
		(13 "F.Paste" user "Package Geometry/Pastemask Top")
		(15 "B.Paste" user "Package Geometry/Pastemask Bottom")
		(5 "F.SilkS" user "Ref Des/Silkscreen Top")
		(7 "B.SilkS" user "Ref Des/Silkscreen Bottom")
		(1 "F.Mask" user "Board Geometry/Soldermask Top")
		(3 "B.Mask" user "Board Geometry/Soldermask Bottom")
		(17 "Dwgs.User" user "User.Drawings")
		(19 "Cmts.User" user "User.Comments")
		(21 "Eco1.User" user "User.Eco1")
		(23 "Eco2.User" user "User.Eco2")
		(25 "Edge.Cuts" user "Board Geometry/Outline")
		(27 "Margin" user)
		(31 "F.CrtYd" user "Package Geometry/Place Bound Top")
		(29 "B.CrtYd" user "Package Geometry/Place Bound Bottom")
		(35 "F.Fab" user "Ref Des/Assembly Top")
		(33 "B.Fab" user "Ref Des/Assembly Bottom")
	)
	(footprint ""
		(layer "F.Cu")
		(at 386.2451 -68.8848 180)
		(property "Reference" "C7E13"
			(at 0 0 180)
			(layer "F.SilkS")
			(hide yes)
			(effects
				(font
					(size 1.27 1.27)
				)
			)
		)
		(property "Value" "*"
			(at -0.0762 -6.2357 180)
			(unlocked yes)
			(layer "F.Fab")
			(hide yes)
			(effects
				(font
					(size 1.27 1.016)
					(thickness 0.1524)
				)
			)
		)
		(property "Device Type" "SC22U16V5MX-4-GP_SMD-BCG5-SC22A"
			(at -0.0762 -8.2677 180)
			(unlocked yes)
			(layer "F.Fab")
			(hide yes)
			(effects
				(font
					(size 1.27 1.016)
					(thickness 0.1524)
				)
			)
		)
		(duplicate_pad_numbers_are_jumpers no)
		(fp_line
			(start 0.635 0)
			(end -0.635 0)
			(stroke
				(width 0.508)
				(type default)
			)
			(layer "F.SilkS")
		)
		(fp_rect
			(start -0.9652 1.778)
			(end 0.9652 -1.778)
			(stroke
				(width 0)
				(type default)
			)
			(fill no)
			(layer "F.CrtYd")
		)
		(fp_poly
			(pts
				(xy -0.9652 -1.778) (xy 0.9652 -1.778) (xy 0.9652 1.778) (xy -0.9652 1.778)
			)
			(stroke
				(width 0)
				(type default)
			)
			(fill no)
			(layer "F.Fab")
		)
		(pad "1" smd rect
			(at 0 -0.9652 180)
			(size 1.397 1.143)
			(layers "F.Cu" "F.Mask" "F.Paste")
			(net "VR_FET_SW_P5V_STBY_PVIN")
		)
		(pad "2" smd rect
			(at 0 0.9652 180)
			(size 1.397 1.143)
			(layers "F.Cu" "F.Mask" "F.Paste")
			(net "GND")
		)
	)
	(footprint ""
		(layer "F.Cu")
		(at 94.45244 -77.636116)
		(property "Reference" "C2D20"
			(at 0 0 0)
			(layer "F.SilkS")
			(hide yes)
			(effects
				(font
					(size 1.27 1.27)
				)
			)
		)
		(property "Value" ""
			(at 0 0 0)
			(layer "F.Fab")
			(effects
				(font
					(size 1.27 1.27)
				)
			)
		)
		(duplicate_pad_numbers_are_jumpers no)
		(fp_poly
			(pts
				(xy -0.4953 -0.2032) (xy 0.4953 -0.2032) (xy 0.4953 1.6002) (xy -0.4953 1.6002)
			)
			(stroke
				(width 0)
				(type default)
			)
			(fill no)
			(layer "F.CrtYd")
		)
		(fp_line
			(start -0.4953 -0.2032)
			(end 0.4953 -0.2032)
			(stroke
				(width 0.1)
				(type default)
			)
			(layer "F.Fab")
		)
		(fp_line
			(start -0.4953 1.6002)
			(end -0.4953 -0.2032)
			(stroke
				(width 0.1)
				(type default)
			)
			(layer "F.Fab")
		)
		(fp_line
			(start 0.4953 -0.2032)
			(end 0.4953 1.6002)
			(stroke
				(width 0.1)
				(type default)
			)
			(layer "F.Fab")
		)
		(fp_line
			(start 0.4953 1.6002)
			(end -0.4953 1.6002)
			(stroke
				(width 0.1)
				(type default)
			)
			(layer "F.Fab")
		)
		(pad "1" smd rect
			(at 0 0)
			(size 0.762 0.889)
			(layers "F.Cu" "F.Mask" "F.Paste")
			(net "PVCCIN_CPU1")
		)
		(pad "2" smd rect
			(at 0 1.397)
			(size 0.762 0.889)
			(layers "F.Cu" "F.Mask" "F.Paste")
			(net "GND")
		)
		(zone
			(layer "F.Cu")
			(hatch none 0.5)
			(connect_pads
				(clearance 0)
			)
			(min_thickness 0.25)
			(keepout
				(tracks not_allowed)
				(vias allowed)
				(pads allowed)
				(copperpour not_allowed)
				(footprints allowed)
			)
			(placement
				(enabled no)
				(sheetname "")
			)
			(fill
				(thermal_gap 0.5)
				(thermal_bridge_width 0.5)
				(island_removal_mode 0)
			)
			(polygon
				(pts
					(xy 94.07144 -77.191616) (xy 94.83344 -77.191616) (xy 94.83344 -76.683616) (xy 94.07144 -76.683616)
				)
			)
		)
	)
	(footprint ""
		(layer "F.Cu")
		(at 99.43084 -77.636116)
		(property "Reference" "C2D24"
			(at 0 0 0)
			(layer "F.SilkS")
			(hide yes)
			(effects
				(font
					(size 1.27 1.27)
				)
			)
		)
		(property "Value" ""
			(at 0 0 0)
			(layer "F.Fab")
			(effects
				(font
					(size 1.27 1.27)
				)
			)
		)
		(duplicate_pad_numbers_are_jumpers no)
		(fp_poly
			(pts
				(xy -0.4953 -0.2032) (xy 0.4953 -0.2032) (xy 0.4953 1.6002) (xy -0.4953 1.6002)
			)
			(stroke
				(width 0)
				(type default)
			)
			(fill no)
			(layer "F.CrtYd")
		)
		(fp_line
			(start -0.4953 -0.2032)
			(end 0.4953 -0.2032)
			(stroke
				(width 0.1)
				(type default)
			)
			(layer "F.Fab")
		)
		(fp_line
			(start -0.4953 1.6002)
			(end -0.4953 -0.2032)
			(stroke
				(width 0.1)
				(type default)
			)
			(layer "F.Fab")
		)
		(fp_line
			(start 0.4953 -0.2032)
			(end 0.4953 1.6002)
			(stroke
				(width 0.1)
				(type default)
			)
			(layer "F.Fab")
		)
		(fp_line
			(start 0.4953 1.6002)
			(end -0.4953 1.6002)
			(stroke
				(width 0.1)
				(type default)
			)
			(layer "F.Fab")
		)
		(pad "1" smd rect
			(at 0 0)
			(size 0.762 0.889)
			(layers "F.Cu" "F.Mask" "F.Paste")
			(net "PVCCIN_CPU1")
		)
		(pad "2" smd rect
			(at 0 1.397)
			(size 0.762 0.889)
			(layers "F.Cu" "F.Mask" "F.Paste")
			(net "GND")
		)
		(zone
			(layer "F.Cu")
			(hatch none 0.5)
			(connect_pads
				(clearance 0)
			)
			(min_thickness 0.25)
			(keepout
				(tracks not_allowed)
				(vias allowed)
				(pads allowed)
				(copperpour not_allowed)
				(footprints allowed)
			)
			(placement
				(enabled no)
				(sheetname "")
			)
			(fill
				(thermal_gap 0.5)
				(thermal_bridge_width 0.5)
				(island_removal_mode 0)
			)
			(polygon
				(pts
					(xy 99.04984 -77.191616) (xy 99.81184 -77.191616) (xy 99.81184 -76.683616) (xy 99.04984 -76.683616)
				)
			)
		)
	)
	(footprint ""
		(layer "F.Cu")
		(at 170.815 -70.6374 180)
		(property "Reference" "C4D31"
			(at 0 0 180)
			(layer "F.SilkS")
			(hide yes)
			(effects
				(font
					(size 1.27 1.27)
				)
			)
		)
		(property "Value" ""
			(at 0 0 180)
			(layer "F.Fab")
			(effects
				(font
					(size 1.27 1.27)
				)
			)
		)
		(duplicate_pad_numbers_are_jumpers no)
		(fp_poly
			(pts
				(xy 0.3048 -0.1016) (xy 0.3048 0.9906) (xy -0.3048 0.9906) (xy -0.3048 -0.1016)
			)
			(stroke
				(width 0)
				(type default)
			)
			(fill no)
			(layer "F.CrtYd")
		)
		(fp_line
			(start 0.3048 0.9906)
			(end 0.3048 -0.1016)
			(stroke
				(width 0.1)
				(type default)
			)
			(layer "F.Fab")
		)
		(fp_line
			(start 0.3048 -0.1016)
			(end -0.3048 -0.1016)
			(stroke
				(width 0.1)
				(type default)
			)
			(layer "F.Fab")
		)
		(fp_line
			(start -0.3048 0.9906)
			(end 0.3048 0.9906)
			(stroke
				(width 0.1)
				(type default)
			)
			(layer "F.Fab")
		)
		(fp_line
			(start -0.3048 -0.1016)
			(end -0.3048 0.9906)
			(stroke
				(width 0.1)
				(type default)
			)
			(layer "F.Fab")
		)
		(pad "1" smd rect
			(at 0 0 180)
			(size 0.508 0.508)
			(layers "F.Cu" "F.Mask" "F.Paste")
			(net "VR_PVCCIO_CPU1_VD12")
		)
		(pad "2" smd rect
			(at 0 0.889 180)
			(size 0.508 0.508)
			(layers "F.Cu" "F.Mask" "F.Paste")
			(net "GND")
		)
		(zone
			(layer "F.Cu")
			(hatch none 0.5)
			(connect_pads
				(clearance 0)
			)
			(min_thickness 0.25)
			(keepout
				(tracks not_allowed)
				(vias allowed)
				(pads allowed)
				(copperpour not_allowed)
				(footprints allowed)
			)
			(placement
				(enabled no)
				(sheetname "")
			)
			(fill
				(thermal_gap 0.5)
				(thermal_bridge_width 0.5)
				(island_removal_mode 0)
			)
			(polygon
				(pts
					(xy 171.069 -71.2724) (xy 170.561 -71.2724) (xy 170.561 -70.8914) (xy 171.069 -70.8914)
				)
			)
		)
		(zone
			(layer "F.Cu")
			(hatch none 0.5)
			(connect_pads
				(clearance 0)
			)
			(min_thickness 0.25)
			(keepout
				(tracks allowed)
				(vias not_allowed)
				(pads allowed)
				(copperpour not_allowed)
				(footprints allowed)
			)
			(placement
				(enabled no)
				(sheetname "")
			)
			(fill
				(thermal_gap 0.5)
				(thermal_bridge_width 0.5)
				(island_removal_mode 0)
			)
			(polygon
				(pts
					(xy 171.069 -70.8914) (xy 170.561 -70.8914) (xy 170.561 -71.2724) (xy 171.069 -71.2724)
				)
			)
		)
	)
)
